# T6G (Grand Teton) — schematic netlist excerpt (pin names and nets, part order shuffled) for the footprints in the layout excerpt that follows; sources: Cadence DE-HDL packaged netlist, KiCad conversion of 04192023_DAF0TMB3IC0_F0TG_MB_C_brd_V02_OCP.brd

D8  Q_LED  IC  pkg SMLF  page 85 : A = BMC_FPGA_LED1_R_N ; C = BMC_FPGA_LED1_N
R4552  Q_RES  100K 1% CHIP  pkg 0402LF  page 241 : A = HPDB_HSC_PWRGD ; B = GND

(kicad_pcb
	(version 20260206)
	(generator "pcbnew")
	(generator_version "10.0")
	(general
		(thickness 1.6)
		(legacy_teardrops no)
	)
	(paper "A4")
	(title_block
		(title "04192023_DAF0TMB3IC0_F0TG_MB_C_brd_V02_OCP.brd")
		(comment 1 "Grand Teton / footprints 601-602 of 8354")
	)
	(layers
		(0 "F.Cu" signal "TOP")
		(4 "In1.Cu" signal "GND")
		(6 "In2.Cu" signal "IN1")
		(8 "In3.Cu" signal "GND1")
		(10 "In4.Cu" signal "IN2")
		(12 "In5.Cu" signal "GND2")
		(14 "In6.Cu" signal "IN3")
		(16 "In7.Cu" signal "GND3")
		(18 "In8.Cu" signal "VCC")
		(20 "In9.Cu" signal "VCC1")
		(22 "In10.Cu" signal "GND4")
		(24 "In11.Cu" signal "IN4")
		(26 "In12.Cu" signal "GND5")
		(28 "In13.Cu" signal "IN5")
		(30 "In14.Cu" signal "GND6")
		(32 "In15.Cu" signal "IN6")
		(34 "In16.Cu" signal "GND7")
		(2 "B.Cu" signal "BOTTOM")
		(9 "F.Adhes" user "F.Adhesive")
		(11 "B.Adhes" user "B.Adhesive")
		(13 "F.Paste" user "Package Geometry/Pastemask Top")
		(15 "B.Paste" user "Package Geometry/Pastemask Bottom")
		(5 "F.SilkS" user "Ref Des/Silkscreen Top")
		(7 "B.SilkS" user "Ref Des/Silkscreen Bottom")
		(1 "F.Mask" user "Board Geometry/Soldermask Top")
		(3 "B.Mask" user "Board Geometry/Soldermask Bottom")
		(17 "Dwgs.User" user "User.Drawings")
		(19 "Cmts.User" user "User.Comments")
		(21 "Eco1.User" user "User.Eco1")
		(23 "Eco2.User" user "User.Eco2")
		(25 "Edge.Cuts" user "Board Geometry/Outline")
		(27 "Margin" user)
		(31 "F.CrtYd" user "Package Geometry/Place Bound Top")
		(29 "B.CrtYd" user "Package Geometry/Place Bound Bottom")
		(35 "F.Fab" user "Ref Des/Assembly Top")
		(33 "B.Fab" user "Ref Des/Assembly Bottom")
	)
	(footprint ""
		(layer "F.Cu")
		(at 278.006556 -438.001664 90)
		(property "Reference" "R4552"
			(at 0 0 90)
			(layer "F.SilkS")
			(hide yes)
			(effects
				(font
					(size 1.27 1.27)
				)
			)
		)
		(property "Value" ""
			(at 0 0 90)
			(layer "F.Fab")
			(effects
				(font
					(size 1.27 1.27)
				)
			)
		)
		(duplicate_pad_numbers_are_jumpers no)
		(fp_line
			(start 0.7874 -0.4064)
			(end 0.7874 0.4064)
			(stroke
				(width 0.1524)
				(type default)
			)
			(layer "F.SilkS")
		)
		(fp_line
			(start -0.7874 -0.4064)
			(end 0.7874 -0.4064)
			(stroke
				(width 0.1524)
				(type default)
			)
			(layer "F.SilkS")
		)
		(fp_line
			(start 0.7874 0.4064)
			(end -0.7874 0.4064)
			(stroke
				(width 0.1524)
				(type default)
			)
			(layer "F.SilkS")
		)
		(fp_line
			(start -0.7874 0.4064)
			(end -0.7874 -0.4064)
			(stroke
				(width 0.1524)
				(type default)
			)
			(layer "F.SilkS")
		)
		(fp_line
			(start -0.12065 -0.305054)
			(end -0.12065 -0.2794)
			(stroke
				(width 0.1)
				(type default)
			)
			(layer "F.Fab")
		)
		(fp_line
			(start -0.67945 -0.305054)
			(end -0.12065 -0.305054)
			(stroke
				(width 0.1)
				(type default)
			)
			(layer "F.Fab")
		)
		(fp_line
			(start 0.67945 -0.3048)
			(end 0.67945 0.3048)
			(stroke
				(width 0.1)
				(type default)
			)
			(layer "F.Fab")
		)
		(fp_line
			(start 0.12065 -0.3048)
			(end 0.67945 -0.3048)
			(stroke
				(width 0.1)
				(type default)
			)
			(layer "F.Fab")
		)
		(fp_line
			(start 0.12065 -0.2794)
			(end 0.12065 -0.3048)
			(stroke
				(width 0.1)
				(type default)
			)
			(layer "F.Fab")
		)
		(fp_line
			(start -0.12065 -0.2794)
			(end 0.12065 -0.2794)
			(stroke
				(width 0.1)
				(type default)
			)
			(layer "F.Fab")
		)
		(fp_line
			(start 0.120396 0.2794)
			(end -0.12065 0.2794)
			(stroke
				(width 0.1)
				(type default)
			)
			(layer "F.Fab")
		)
		(fp_line
			(start -0.12065 0.2794)
			(end -0.12065 0.3048)
			(stroke
				(width 0.1)
				(type default)
			)
			(layer "F.Fab")
		)
		(fp_line
			(start 0.67945 0.3048)
			(end 0.120396 0.3048)
			(stroke
				(width 0.1)
				(type default)
			)
			(layer "F.Fab")
		)
		(fp_line
			(start 0.120396 0.3048)
			(end 0.120396 0.2794)
			(stroke
				(width 0.1)
				(type default)
			)
			(layer "F.Fab")
		)
		(fp_line
			(start -0.12065 0.3048)
			(end -0.67945 0.3048)
			(stroke
				(width 0.1)
				(type default)
			)
			(layer "F.Fab")
		)
		(fp_line
			(start -0.67945 0.3048)
			(end -0.67945 -0.305054)
			(stroke
				(width 0.1)
				(type default)
			)
			(layer "F.Fab")
		)
		(pad "1" smd circle
			(at -0.40005 0 90)
			(size 0 0)
			(layers "F.Cu" "F.Mask" "F.Paste")
			(net "HPDB_HSC_PWRGD")
		)
		(pad "2" smd circle
			(at 0.40005 0 90)
			(size 0 0)
			(layers "F.Cu" "F.Mask" "F.Paste")
			(net "GND")
		)
	)
	(footprint ""
		(layer "F.Cu")
		(at 333.65948 -16.178276 90)
		(property "Reference" "D8"
			(at -3.48869 -0.212344 90)
			(unlocked yes)
			(layer "F.SilkS")
			(effects
				(font
					(size 0.7874 0.5842)
					(thickness 0.1524)
				)
				(justify left)
			)
		)
		(property "Value" ""
			(at 0 0 90)
			(layer "F.Fab")
			(effects
				(font
					(size 1.27 1.27)
				)
			)
		)
		(duplicate_pad_numbers_are_jumpers no)
		(fp_line
			(start 1.778 -0.5588)
			(end 1.3208 -0.5588)
			(stroke
				(width 0.1524)
				(type default)
			)
			(layer "F.SilkS")
		)
		(fp_line
			(start 1.778 -0.5588)
			(end 1.778 0.5588)
			(stroke
				(width 0.1524)
				(type default)
			)
			(layer "F.SilkS")
		)
		(fp_line
			(start 1.4732 -0.5588)
			(end 1.4732 0.5588)
			(stroke
				(width 0.1524)
				(type default)
			)
			(layer "F.SilkS")
		)
		(fp_line
			(start 1.3208 -0.5588)
			(end 1.3208 0.5588)
			(stroke
				(width 0.1524)
				(type default)
			)
			(layer "F.SilkS")
		)
		(fp_line
			(start -1.3208 -0.5588)
			(end 1.3208 -0.5588)
			(stroke
				(width 0.1524)
				(type default)
			)
			(layer "F.SilkS")
		)
		(fp_line
			(start 1.778 0.5588)
			(end 1.3208 0.5588)
			(stroke
				(width 0.1524)
				(type default)
			)
			(layer "F.SilkS")
		)
		(fp_line
			(start 1.6256 0.5588)
			(end 1.6256 -0.5588)
			(stroke
				(width 0.1524)
				(type default)
			)
			(layer "F.SilkS")
		)
		(fp_line
			(start 1.3208 0.5588)
			(end -1.3208 0.5588)
			(stroke
				(width 0.1524)
				(type default)
			)
			(layer "F.SilkS")
		)
		(fp_line
			(start -1.3208 0.5588)
			(end -1.3208 -0.5588)
			(stroke
				(width 0.1524)
				(type default)
			)
			(layer "F.SilkS")
		)
		(fp_line
			(start 0.899922 -0.40005)
			(end 0.899922 0.40005)
			(stroke
				(width 0.1)
				(type default)
			)
			(layer "F.Fab")
		)
		(fp_line
			(start -0.899922 -0.40005)
			(end 0.899922 -0.40005)
			(stroke
				(width 0.1)
				(type default)
			)
			(layer "F.Fab")
		)
		(fp_line
			(start 0.899922 0.40005)
			(end -0.899922 0.40005)
			(stroke
				(width 0.1)
				(type default)
			)
			(layer "F.Fab")
		)
		(fp_line
			(start -0.899922 0.40005)
			(end -0.899922 -0.40005)
			(stroke
				(width 0.1)
				(type default)
			)
			(layer "F.Fab")
		)
		(fp_text user "-"
			(at 1.651 -0.86233 90)
			(unlocked yes)
			(layer "F.SilkS")
			(effects
				(font
					(size 1.905 1.4224)
					(thickness 0.1524)
				)
				(justify left)
			)
		)
		(fp_text user "+"
			(at -2.466086 0.324104 90)
			(unlocked yes)
			(layer "F.SilkS")
			(effects
				(font
					(size 1.905 1.4224)
					(thickness 0.1524)
				)
				(justify left)
			)
		)
		(fp_text user "-"
			(at 1.651 -0.22225 90)
			(unlocked yes)
			(layer "F.Fab")
			(effects
				(font
					(size 1.905 1.4224)
					(thickness 0.1524)
				)
				(justify left)
			)
		)
		(fp_text user "+"
			(at -2.6162 -0.22225 90)
			(unlocked yes)
			(layer "F.Fab")
			(effects
				(font
					(size 1.905 1.4224)
					(thickness 0.1524)
				)
				(justify left)
			)
		)
		(pad "A" smd rect
			(at -0.750062 0 90)
			(size 0.8128 0.8128)
			(layers "F.Cu" "F.Mask" "F.Paste")
			(net "BMC_FPGA_LED1_R_N")
		)
		(pad "C" smd rect
			(at 0.750062 0 90)
			(size 0.8128 0.8128)
			(layers "F.Cu" "F.Mask" "F.Paste")
			(net "BMC_FPGA_LED1_N")
		)
	)
)
